(kicad_pcb
	(version 20241229)
	(generator "pcbnew")
	(generator_version "9.0")
	(general
		(thickness 1.61)
		(legacy_teardrops no)
	)
	(paper "A3")
	(title_block
		(title "SO-DIMM DDR5 Tester")
		(date "2025-11-26")
		(rev "1.3.0")
		(comment 9 "footprints 431-436 of 627")
	)
	(layers
		(0 "F.Cu" signal)
		(4 "In1.Cu" power)
		(6 "In2.Cu" mixed)
		(8 "In3.Cu" power)
		(10 "In4.Cu" mixed)
		(12 "In5.Cu" power)
		(14 "In6.Cu" mixed)
		(16 "In7.Cu" power)
		(18 "In8.Cu" power)
		(20 "In9.Cu" mixed)
		(22 "In10.Cu" power)
		(2 "B.Cu" signal)
		(9 "F.Adhes" user "F.Adhesive")
		(11 "B.Adhes" user "B.Adhesive")
		(13 "F.Paste" user)
		(15 "B.Paste" user)
		(5 "F.SilkS" user "F.Silkscreen")
		(7 "B.SilkS" user "B.Silkscreen")
		(1 "F.Mask" user)
		(3 "B.Mask" user)
		(17 "Dwgs.User" user "User.Drawings")
		(19 "Cmts.User" user "User.Comments")
		(21 "Eco1.User" user "User.Eco1")
		(23 "Eco2.User" user "User.Eco2")
		(25 "Edge.Cuts" user)
		(27 "Margin" user)
		(31 "F.CrtYd" user "F.Courtyard")
		(29 "B.CrtYd" user "B.Courtyard")
		(35 "F.Fab" user)
		(33 "B.Fab" user)
	)
	(footprint "antmicro-footprints:Fiducial_1mm_Mask2mm"
		(layer "B.Cu")
		(at 197.010501 197.696 180)
		(descr "Circular Fiducial, 1mm bare copper, 3mm soldermask opening")
		(tags "fiducial")
		(property "Reference" "FID1002"
			(at 0 1.4 0)
			(layer "B.SilkS")
			(hide yes)
			(effects
				(font
					(size 0.7 0.7)
					(thickness 0.15)
				)
				(justify left bottom mirror)
			)
		)
		(property "Value" "Fiducial_1mm_Mask2mm"
			(at 0 -2.2 0)
			(layer "B.Fab")
			(effects
				(font
					(size 0.7 0.7)
					(thickness 0.15)
				)
				(justify left bottom mirror)
			)
		)
		(property "Author" "Antmicro"
			(at 394.021002 395.392 0)
			(layer "B.Fab")
			(hide yes)
			(effects
				(font
					(size 1 1)
					(thickness 0.15)
				)
				(justify mirror)
			)
		)
		(property "License" "Apache-2.0"
			(at 394.021002 395.392 0)
			(layer "B.Fab")
			(hide yes)
			(effects
				(font
					(size 1 1)
					(thickness 0.15)
				)
				(justify mirror)
			)
		)
		(property "MPN" ""
			(at 394.021002 395.392 0)
			(layer "B.Fab")
			(hide yes)
			(effects
				(font
					(size 1 1)
					(thickness 0.15)
				)
				(justify mirror)
			)
		)
		(property "Manufacturer" ""
			(at 394.021002 395.392 0)
			(layer "B.Fab")
			(hide yes)
			(effects
				(font
					(size 1 1)
					(thickness 0.15)
				)
				(justify mirror)
			)
		)
		(sheetfile "sodimm-ddr5-tester.kicad_sch")
		(attr board_only exclude_from_pos_files exclude_from_bom)
		(fp_circle
			(center 0 0)
			(end 1.24 0)
			(stroke
				(width 0.05)
				(type solid)
			)
			(fill no)
			(layer "B.CrtYd")
		)
		(fp_circle
			(center 0 0)
			(end 0.999 0)
			(stroke
				(width 0.15)
				(type solid)
			)
			(fill no)
			(layer "B.Fab")
		)
		(pad "" smd circle
			(at 0 0 180)
			(size 1 1)
			(layers "B.Cu" "B.Mask")
			(solder_mask_margin 0.5)
			(clearance 0.5)
		)
	)
	(footprint "antmicro-footprints:C_0402_1005Metric"
		(layer "B.Cu")
		(at 93.8 164.4515 180)
		(descr "Capacitor SMD 0402")
		(tags "capacitor SMD 0402")
		(property "Reference" "C161"
			(at 0 0.699 0)
			(layer "B.SilkS")
			(hide yes)
			(effects
				(font
					(size 0.7 0.7)
					(thickness 0.15)
				)
				(justify left bottom mirror)
			)
		)
		(property "Value" "C_100n_0402"
			(at -1.022927 -2.155213 0)
			(layer "B.Fab")
			(effects
				(font
					(size 0.7 0.7)
					(thickness 0.15)
				)
				(justify left bottom mirror)
			)
		)
		(property "Datasheet" "https://www.murata.com/products/productdetail?partno=GRM155R61H104KE14%23"
			(at 0 0 180)
			(layer "F.Fab")
			(hide yes)
			(effects
				(font
					(size 1.27 1.27)
					(thickness 0.15)
				)
			)
		)
		(property "Author" "Antmicro"
			(at 187.6 328.903 0)
			(layer "B.Fab")
			(hide yes)
			(effects
				(font
					(size 1 1)
					(thickness 0.15)
				)
				(justify mirror)
			)
		)
		(property "Dielectric" "X5R"
			(at 187.6 328.903 0)
			(layer "B.Fab")
			(hide yes)
			(effects
				(font
					(size 1 1)
					(thickness 0.15)
				)
				(justify mirror)
			)
		)
		(property "License" "Apache-2.0"
			(at 187.6 328.903 0)
			(layer "B.Fab")
			(hide yes)
			(effects
				(font
					(size 1 1)
					(thickness 0.15)
				)
				(justify mirror)
			)
		)
		(property "MPN" "GRM155R61H104KE14D"
			(at 187.6 328.903 0)
			(layer "B.Fab")
			(hide yes)
			(effects
				(font
					(size 1 1)
					(thickness 0.15)
				)
				(justify mirror)
			)
		)
		(property "Manufacturer" "Murata"
			(at 187.6 328.903 0)
			(layer "B.Fab")
			(hide yes)
			(effects
				(font
					(size 1 1)
					(thickness 0.15)
				)
				(justify mirror)
			)
		)
		(property "Val" "100n"
			(at 187.6 328.903 0)
			(layer "B.Fab")
			(hide yes)
			(effects
				(font
					(size 1 1)
					(thickness 0.15)
				)
				(justify mirror)
			)
		)
		(property "Voltage" "50V"
			(at 187.6 328.903 0)
			(layer "B.Fab")
			(hide yes)
			(effects
				(font
					(size 1 1)
					(thickness 0.15)
				)
				(justify mirror)
			)
		)
		(sheetname "/Ethernet/")
		(sheetfile "ethernet.kicad_sch")
		(attr smd)
		(fp_rect
			(start -0.9659 0.481258)
			(end 0.9649 -0.458742)
			(stroke
				(width 0.05)
				(type solid)
			)
			(fill no)
			(layer "B.CrtYd")
		)
		(fp_line
			(start 0.499 0.25)
			(end 0.499 -0.248)
			(stroke
				(width 0.15)
				(type solid)
			)
			(layer "B.Fab")
		)
		(fp_line
			(start 0.499 -0.248)
			(end -0.499 -0.248)
			(stroke
				(width 0.15)
				(type solid)
			)
			(layer "B.Fab")
		)
		(fp_line
			(start -0.499 0.25)
			(end 0.499 0.25)
			(stroke
				(width 0.15)
				(type solid)
			)
			(layer "B.Fab")
		)
		(fp_line
			(start -0.499 -0.248)
			(end -0.499 0.25)
			(stroke
				(width 0.15)
				(type solid)
			)
			(layer "B.Fab")
		)
		(pad "1" smd roundrect
			(at -0.484 0 180)
			(size 0.59 0.64)
			(layers "B.Cu" "B.Mask" "B.Paste")
			(roundrect_rratio 0.25)
			(net 1 "GND")
			(pintype "passive")
		)
		(pad "2" smd roundrect
			(at 0.484 0 180)
			(size 0.59 0.64)
			(layers "B.Cu" "B.Mask" "B.Paste")
			(roundrect_rratio 0.25)
			(net 200 "+3V3")
			(pintype "passive")
		)
	)
	(footprint "antmicro-footprints:C_0603_1608Metric"
		(layer "B.Cu")
		(at 139.575501 174.801 180)
		(descr "Capacitor SMD 0603")
		(tags "capacitor 0603")
		(property "Reference" "C18"
			(at 0 0.9 0)
			(layer "B.SilkS")
			(hide yes)
			(effects
				(font
					(size 0.7 0.7)
					(thickness 0.15)
				)
				(justify left bottom mirror)
			)
		)
		(property "Value" "C_47u_0603"
			(at 0 -1.6 0)
			(layer "B.Fab")
			(effects
				(font
					(size 0.7 0.7)
					(thickness 0.15)
				)
				(justify left bottom mirror)
			)
		)
		(property "Datasheet" "https://www.murata.com/products/productdetail?partno=GRM188R60J476ME15%23"
			(at 0 0 180)
			(layer "F.Fab")
			(hide yes)
			(effects
				(font
					(size 1.27 1.27)
					(thickness 0.15)
				)
			)
		)
		(property "Author" "Antmicro"
			(at 279.151002 349.602 0)
			(layer "B.Fab")
			(hide yes)
			(effects
				(font
					(size 1 1)
					(thickness 0.15)
				)
				(justify mirror)
			)
		)
		(property "Dielectric" ""
			(at 279.151002 349.602 0)
			(layer "B.Fab")
			(hide yes)
			(effects
				(font
					(size 1 1)
					(thickness 0.15)
				)
				(justify mirror)
			)
		)
		(property "License" "Apache-2.0"
			(at 279.151002 349.602 0)
			(layer "B.Fab")
			(hide yes)
			(effects
				(font
					(size 1 1)
					(thickness 0.15)
				)
				(justify mirror)
			)
		)
		(property "MPN" "GRM188R60J476ME15D"
			(at 279.151002 349.602 0)
			(layer "B.Fab")
			(hide yes)
			(effects
				(font
					(size 1 1)
					(thickness 0.15)
				)
				(justify mirror)
			)
		)
		(property "Manufacturer" "Murata"
			(at 279.151002 349.602 0)
			(layer "B.Fab")
			(hide yes)
			(effects
				(font
					(size 1 1)
					(thickness 0.15)
				)
				(justify mirror)
			)
		)
		(property "Val" "47u"
			(at 279.151002 349.602 0)
			(layer "B.Fab")
			(hide yes)
			(effects
				(font
					(size 1 1)
					(thickness 0.15)
				)
				(justify mirror)
			)
		)
		(property "Voltage" ""
			(at 279.151002 349.602 0)
			(layer "B.Fab")
			(hide yes)
			(effects
				(font
					(size 1 1)
					(thickness 0.15)
				)
				(justify mirror)
			)
		)
		(sheetname "/FPGA power/")
		(sheetfile "fpga-power.kicad_sch")
		(attr smd)
		(fp_line
			(start -0.3 0.3)
			(end 0.3 0.3)
			(stroke
				(width 0.15)
				(type solid)
			)
			(layer "B.SilkS")
		)
		(fp_line
			(start -0.3 -0.3)
			(end 0.3 -0.3)
			(stroke
				(width 0.15)
				(type solid)
			)
			(layer "B.SilkS")
		)
		(fp_rect
			(start -1.24 0.7)
			(end 1.24 -0.7)
			(stroke
				(width 0.05)
				(type solid)
			)
			(fill no)
			(layer "B.CrtYd")
		)
		(fp_rect
			(start -0.8 0.4)
			(end 0.8 -0.4)
			(stroke
				(width 0.15)
				(type solid)
			)
			(fill no)
			(layer "B.Fab")
		)
		(pad "1" smd roundrect
			(at -0.7 0 180)
			(size 0.6 0.8)
			(layers "B.Cu" "B.Mask" "B.Paste")
			(roundrect_rratio 0.2)
			(net 188 "+1V8")
			(pintype "passive")
		)
		(pad "2" smd roundrect
			(at 0.7 0 180)
			(size 0.6 0.8)
			(layers "B.Cu" "B.Mask" "B.Paste")
			(roundrect_rratio 0.2)
			(net 1 "GND")
			(pintype "passive")
		)
	)
	(footprint "antmicro-footprints:C_0402_1005Metric"
		(layer "B.Cu")
		(at 141.875501 180.301)
		(descr "Capacitor SMD 0402 (1005 Metric), square (rectangular) end terminal, IPC_7351 nominal, (Body size source: IPC-SM-782 page 76, https://www.pcb-3d.com/wordpress/wp-content/uploads/ipc-sm-782a_amendment_1_and_2.pdf)")
		(tags "capacitor 0402")
		(property "Reference" "C28"
			(at 0 1.17 180)
			(layer "B.SilkS")
			(hide yes)
			(effects
				(font
					(size 0.7 0.7)
					(thickness 0.15)
				)
				(justify left bottom mirror)
			)
		)
		(property "Value" "C_100n_0402"
			(at 0 -1.169 180)
			(layer "B.Fab")
			(effects
				(font
					(size 0.7 0.7)
					(thickness 0.15)
				)
				(justify left bottom mirror)
			)
		)
		(property "Datasheet" "https://www.murata.com/products/productdetail?partno=GRM155R61H104KE14%23"
			(at 0 0 0)
			(layer "F.Fab")
			(hide yes)
			(effects
				(font
					(size 1.27 1.27)
					(thickness 0.15)
				)
			)
		)
		(property "Author" "Antmicro"
			(at 0 0 0)
			(layer "B.Fab")
			(hide yes)
			(effects
				(font
					(size 1 1)
					(thickness 0.15)
				)
				(justify mirror)
			)
		)
		(property "Dielectric" "X5R"
			(at 0 0 0)
			(layer "B.Fab")
			(hide yes)
			(effects
				(font
					(size 1 1)
					(thickness 0.15)
				)
				(justify mirror)
			)
		)
		(property "License" "Apache-2.0"
			(at 0 0 0)
			(layer "B.Fab")
			(hide yes)
			(effects
				(font
					(size 1 1)
					(thickness 0.15)
				)
				(justify mirror)
			)
		)
		(property "MPN" "GRM155R61H104KE14D"
			(at 0 0 0)
			(layer "B.Fab")
			(hide yes)
			(effects
				(font
					(size 1 1)
					(thickness 0.15)
				)
				(justify mirror)
			)
		)
		(property "Manufacturer" "Murata"
			(at 0 0 0)
			(layer "B.Fab")
			(hide yes)
			(effects
				(font
					(size 1 1)
					(thickness 0.15)
				)
				(justify mirror)
			)
		)
		(property "Val" "100n"
			(at 0 0 0)
			(layer "B.Fab")
			(hide yes)
			(effects
				(font
					(size 1 1)
					(thickness 0.15)
				)
				(justify mirror)
			)
		)
		(property "Voltage" "50V"
			(at 0 0 0)
			(layer "B.Fab")
			(hide yes)
			(effects
				(font
					(size 1 1)
					(thickness 0.15)
				)
				(justify mirror)
			)
		)
		(sheetname "/FPGA power/")
		(sheetfile "fpga-power.kicad_sch")
		(attr smd)
		(fp_rect
			(start -0.9656 0.4572)
			(end 0.9652 -0.4828)
			(stroke
				(width 0.05)
				(type solid)
			)
			(fill no)
			(layer "B.CrtYd")
		)
		(fp_line
			(start -0.5 -0.248)
			(end -0.5 0.25)
			(stroke
				(width 0.15)
				(type solid)
			)
			(layer "B.Fab")
		)
		(fp_line
			(start -0.5 0.25)
			(end 0.498 0.25)
			(stroke
				(width 0.15)
				(type solid)
			)
			(layer "B.Fab")
		)
		(fp_line
			(start 0.498 -0.248)
			(end -0.5 -0.248)
			(stroke
				(width 0.15)
				(type solid)
			)
			(layer "B.Fab")
		)
		(fp_line
			(start 0.498 0.25)
			(end 0.498 -0.248)
			(stroke
				(width 0.15)
				(type solid)
			)
			(layer "B.Fab")
		)
		(pad "1" smd roundrect
			(at -0.5 0 270)
			(size 0.6 0.6)
			(layers "B.Cu" "B.Mask" "B.Paste")
			(roundrect_rratio 0.25)
			(net 1 "GND")
			(pintype "passive")
		)
		(pad "2" smd roundrect
			(at 0.498 0)
			(size 0.6 0.6)
			(layers "B.Cu" "B.Mask" "B.Paste")
			(roundrect_rratio 0.25)
			(net 200 "+3V3")
			(pintype "passive")
		)
	)
	(footprint "antmicro-footprints:TP_SMD_1mm"
		(layer "B.Cu")
		(at 186.4 167.45 180)
		(property "Reference" "TP30"
			(at 0 0.731898 0)
			(layer "B.SilkS")
			(hide yes)
			(effects
				(font
					(size 0.7 0.7)
					(thickness 0.15)
				)
				(justify left bottom mirror)
			)
		)
		(property "Value" "TP_1mm_SMD"
			(at 0 -1.4 0)
			(layer "B.Fab")
			(effects
				(font
					(size 0.7 0.7)
					(thickness 0.15)
				)
				(justify left bottom mirror)
			)
		)
		(property "MPN" ""
			(at 0 0 0)
			(unlocked yes)
			(layer "B.Fab")
			(hide yes)
			(effects
				(font
					(size 1 1)
					(thickness 0.15)
				)
				(justify mirror)
			)
		)
		(property "Manufacturer" ""
			(at 0 0 0)
			(unlocked yes)
			(layer "B.Fab")
			(hide yes)
			(effects
				(font
					(size 1 1)
					(thickness 0.15)
				)
				(justify mirror)
			)
		)
		(property "Author" "Antmicro"
			(at 0 0 0)
			(unlocked yes)
			(layer "B.Fab")
			(hide yes)
			(effects
				(font
					(size 1 1)
					(thickness 0.15)
				)
				(justify mirror)
			)
		)
		(property "License" "Apache-2.0"
			(at 0 0 0)
			(unlocked yes)
			(layer "B.Fab")
			(hide yes)
			(effects
				(font
					(size 1 1)
					(thickness 0.15)
				)
				(justify mirror)
			)
		)
		(sheetname "/Supply/")
		(sheetfile "supply.kicad_sch")
		(attr exclude_from_pos_files)
		(fp_circle
			(center 0 0)
			(end 0.6 0)
			(stroke
				(width 0.05)
				(type default)
			)
			(fill no)
			(layer "B.CrtYd")
		)
		(fp_text user "Author: Antmicro"
			(at -0.5 -4 0)
			(layer "B.Fab")
			(effects
				(font
					(size 0.7 0.7)
					(thickness 0.15)
				)
				(justify left bottom mirror)
			)
		)
		(fp_text user "${REFERENCE}"
			(at -0.5 -2.8 0)
			(layer "B.Fab")
			(effects
				(font
					(size 0.7 0.7)
					(thickness 0.15)
				)
				(justify left bottom mirror)
			)
		)
		(fp_text user "License: Apache-2.0"
			(at -0.5 -5.2 0)
			(layer "B.Fab")
			(effects
				(font
					(size 0.7 0.7)
					(thickness 0.15)
				)
				(justify left bottom mirror)
			)
		)
		(pad "1" smd circle
			(at 0 0 180)
			(size 1 1)
			(layers "B.Cu" "B.Mask")
			(net 200 "+3V3")
			(pinfunction "1")
			(pintype "passive")
		)
	)
	(footprint "antmicro-footprints:R_0402_1005Metric_EIA"
		(layer "B.Cu")
		(at 143.375001 170.8025 90)
		(descr "Resistor SMD 0402 (1005 Metric), square (rectangular) end terminal, IPC_7351 nominal, (Body size source: IPC-SM-782 page 76, https://www.pcb-3d.com/wordpress/wp-content/uploads/ipc-sm-782a_amendment_1_and_2.pdf)")
		(tags "resistor 0402")
		(property "Reference" "R133"
			(at 0 1.17 270)
			(layer "B.SilkS")
			(hide yes)
			(effects
				(font
					(size 0.7 0.7)
					(thickness 0.15)
				)
				(justify left bottom mirror)
			)
		)
		(property "Value" "R_80R6_0402_EIA"
			(at 0 -1.169 270)
			(layer "B.Fab")
			(effects
				(font
					(size 0.7 0.7)
					(thickness 0.15)
				)
				(justify left bottom mirror)
			)
		)
		(property "Datasheet" "https://www.bourns.com/docs/product-datasheets/cr.pdf"
			(at 0 0 90)
			(layer "F.Fab")
			(hide yes)
			(effects
				(font
					(size 1.27 1.27)
					(thickness 0.15)
				)
			)
		)
		(property "Author" "Antmicro"
			(at 314.177501 27.427499 0)
			(layer "B.Fab")
			(hide yes)
			(effects
				(font
					(size 1 1)
					(thickness 0.15)
				)
				(justify mirror)
			)
		)
		(property "License" "Apache-2.0"
			(at 314.177501 27.427499 0)
			(layer "B.Fab")
			(hide yes)
			(effects
				(font
					(size 1 1)
					(thickness 0.15)
				)
				(justify mirror)
			)
		)
		(property "MPN" "MC00625W0402180R6"
			(at 314.177501 27.427499 0)
			(layer "B.Fab")
			(hide yes)
			(effects
				(font
					(size 1 1)
					(thickness 0.15)
				)
				(justify mirror)
			)
		)
		(property "Manufacturer" "Multicomp Pro"
			(at 314.177501 27.427499 0)
			(layer "B.Fab")
			(hide yes)
			(effects
				(font
					(size 1 1)
					(thickness 0.15)
				)
				(justify mirror)
			)
		)
		(property "Tolerance" "1%"
			(at 314.177501 27.427499 0)
			(layer "B.Fab")
			(hide yes)
			(effects
				(font
					(size 1 1)
					(thickness 0.15)
				)
				(justify mirror)
			)
		)
		(property "Val" "80R6"
			(at 314.177501 27.427499 0)
			(layer "B.Fab")
			(hide yes)
			(effects
				(font
					(size 1 1)
					(thickness 0.15)
				)
				(justify mirror)
			)
		)
		(sheetname "/FPGA banks HP/")
		(sheetfile "fpga-banks-32-34.kicad_sch")
		(attr smd)
		(fp_line
			(start 0.9652 -0.45)
			(end -0.95 -0.45)
			(stroke
				(width 0.05)
				(type solid)
			)
			(layer "B.CrtYd")
		)
		(fp_line
			(start -0.95 -0.45)
			(end -0.95 0.46)
			(stroke
				(width 0.05)
				(type solid)
			)
			(layer "B.CrtYd")
		)
		(fp_line
			(start 0.9652 0.46)
			(end 0.9652 -0.45)
			(stroke
				(width 0.05)
				(type solid)
			)
			(layer "B.CrtYd")
		)
		(fp_line
			(start -0.95 0.46)
			(end 0.9652 0.46)
			(stroke
				(width 0.05)
				(type solid)
			)
			(layer "B.CrtYd")
		)
		(fp_line
			(start 0.499 -0.249)
			(end -0.5 -0.249)
			(stroke
				(width 0.15)
				(type solid)
			)
			(layer "B.Fab")
		)
		(fp_line
			(start -0.5 -0.249)
			(end -0.5 0.25)
			(stroke
				(width 0.15)
				(type solid)
			)
			(layer "B.Fab")
		)
		(fp_line
			(start 0.499 0.25)
			(end 0.499 -0.249)
			(stroke
				(width 0.15)
				(type solid)
			)
			(layer "B.Fab")
		)
		(fp_line
			(start -0.5 0.25)
			(end 0.499 0.25)
			(stroke
				(width 0.15)
				(type solid)
			)
			(layer "B.Fab")
		)
		(pad "1" smd roundrect
			(at -0.5 0)
			(size 0.6 0.6)
			(layers "B.Cu" "B.Mask" "B.Paste")
			(roundrect_rratio 0.25)
			(net 684 "/FPGA banks HP/VRN")
			(pintype "passive")
		)
		(pad "2" smd roundrect
			(at 0.499 0 90)
			(size 0.6 0.6)
			(layers "B.Cu" "B.Mask" "B.Paste")
			(roundrect_rratio 0.25)
			(net 206 "+1V1")
			(pintype "passive")
		)
	)
)
